# BASEBOARD_FAB2 (Tioga Pass) — schematic netlist excerpt (pin names and nets, part order shuffled) for the footprints in the layout excerpt that follows; sources: Cadence DE-HDL packaged netlist, KiCad conversion of Wiwynn_Tioga_Pass_MB.brd

Q2T2  FET_N  2N7002 FET  pkg SOT23LF  page 157
  GATE  = H_CPU0_FAST_WAKE
  SRC  = GND
  DRN  = H_CPU0_FAST_WAKE_LVT3_N

C9G20  CAP  47.0PF 50V 5% COG  pkg 0402LF  page 169 : A = A_P3V3_STBY_SCALED ; B = GND
C2M2  CAP_A  22.0UF 4V 20% X6S  pkg 0603V  page 130 : A = P1V8_PCH_STBY ; B = GND

(kicad_pcb
	(version 20260206)
	(generator "pcbnew")
	(generator_version "10.0")
	(general
		(thickness 1.6)
		(legacy_teardrops no)
	)
	(paper "A4")
	(title_block
		(title "Wiwynn_Tioga_Pass_MB.brd")
		(comment 1 "Tioga Pass / footprints 2978-2980 of 4770")
	)
	(layers
		(0 "F.Cu" signal "TOP")
		(4 "In1.Cu" signal "L2GND")
		(6 "In2.Cu" signal "L3")
		(8 "In3.Cu" signal "L4GND")
		(10 "In4.Cu" signal "L5")
		(12 "In5.Cu" signal "L6GND")
		(14 "In6.Cu" signal "L7VCC")
		(16 "In7.Cu" signal "L8VCC")
		(18 "In8.Cu" signal "L9GND")
		(20 "In9.Cu" signal "L10")
		(22 "In10.Cu" signal "L11GND")
		(24 "In11.Cu" signal "L12")
		(26 "In12.Cu" signal "L13GND")
		(2 "B.Cu" signal "BOTTOM")
		(9 "F.Adhes" user "F.Adhesive")
		(11 "B.Adhes" user "B.Adhesive")
		(13 "F.Paste" user "Package Geometry/Pastemask Top")
		(15 "B.Paste" user "Package Geometry/Pastemask Bottom")
		(5 "F.SilkS" user "Ref Des/Silkscreen Top")
		(7 "B.SilkS" user "Ref Des/Silkscreen Bottom")
		(1 "F.Mask" user "Board Geometry/Soldermask Top")
		(3 "B.Mask" user "Board Geometry/Soldermask Bottom")
		(17 "Dwgs.User" user "User.Drawings")
		(19 "Cmts.User" user "User.Comments")
		(21 "Eco1.User" user "User.Eco1")
		(23 "Eco2.User" user "User.Eco2")
		(25 "Edge.Cuts" user "Board Geometry/Outline")
		(27 "Margin" user)
		(31 "F.CrtYd" user "Package Geometry/Place Bound Top")
		(29 "B.CrtYd" user "Package Geometry/Place Bound Bottom")
		(35 "F.Fab" user "Ref Des/Assembly Top")
		(33 "B.Fab" user "Ref Des/Assembly Bottom")
	)
	(footprint ""
		(layer "B.Cu")
		(at 411.0355 -129.413 90)
		(property "Reference" "C2M2"
			(at 0 0 90)
			(layer "B.SilkS")
			(hide yes)
			(effects
				(font
					(size 1.27 1.27)
				)
				(justify mirror)
			)
		)
		(property "Value" ""
			(at 0 0 90)
			(layer "B.Fab")
			(effects
				(font
					(size 1.27 1.27)
				)
				(justify mirror)
			)
		)
		(duplicate_pad_numbers_are_jumpers no)
		(fp_poly
			(pts
				(xy 0.4953 -0.2032) (xy -0.4953 -0.2032) (xy -0.4953 1.6002) (xy 0.4953 1.6002)
			)
			(stroke
				(width 0)
				(type default)
			)
			(fill no)
			(layer "B.CrtYd")
		)
		(fp_line
			(start 0.4953 -0.2032)
			(end -0.4953 -0.2032)
			(stroke
				(width 0.1)
				(type default)
			)
			(layer "B.Fab")
		)
		(fp_line
			(start -0.4953 -0.2032)
			(end -0.4953 1.6002)
			(stroke
				(width 0.1)
				(type default)
			)
			(layer "B.Fab")
		)
		(fp_line
			(start 0.4953 1.6002)
			(end 0.4953 -0.2032)
			(stroke
				(width 0.1)
				(type default)
			)
			(layer "B.Fab")
		)
		(fp_line
			(start -0.4953 1.6002)
			(end 0.4953 1.6002)
			(stroke
				(width 0.1)
				(type default)
			)
			(layer "B.Fab")
		)
		(pad "1" smd rect
			(at 0 0 270)
			(size 0.762 0.889)
			(layers "B.Cu" "B.Mask" "B.Paste")
			(net "P1V8_PCH_STBY")
		)
		(pad "2" smd rect
			(at 0 1.397 270)
			(size 0.762 0.889)
			(layers "B.Cu" "B.Mask" "B.Paste")
			(net "GND")
		)
		(zone
			(layer "B.Cu")
			(hatch none 0.5)
			(connect_pads
				(clearance 0)
			)
			(min_thickness 0.25)
			(keepout
				(tracks not_allowed)
				(vias allowed)
				(pads allowed)
				(copperpour not_allowed)
				(footprints allowed)
			)
			(placement
				(enabled no)
				(sheetname "")
			)
			(fill
				(thermal_gap 0.5)
				(thermal_bridge_width 0.5)
				(island_removal_mode 0)
			)
			(polygon
				(pts
					(xy 411.48 -129.794) (xy 411.48 -129.032) (xy 411.988 -129.032) (xy 411.988 -129.794)
				)
			)
		)
	)
	(footprint ""
		(layer "B.Cu")
		(at 404.913846 -26.489152)
		(property "Reference" "C9G20"
			(at 0 0 0)
			(layer "B.SilkS")
			(hide yes)
			(effects
				(font
					(size 1.27 1.27)
				)
				(justify mirror)
			)
		)
		(property "Value" ""
			(at 0 0 0)
			(layer "B.Fab")
			(effects
				(font
					(size 1.27 1.27)
				)
				(justify mirror)
			)
		)
		(duplicate_pad_numbers_are_jumpers no)
		(fp_poly
			(pts
				(xy -0.3048 -0.1016) (xy -0.3048 0.9906) (xy 0.3048 0.9906) (xy 0.3048 -0.1016)
			)
			(stroke
				(width 0)
				(type default)
			)
			(fill no)
			(layer "B.CrtYd")
		)
		(fp_line
			(start -0.3048 -0.1016)
			(end 0.3048 -0.1016)
			(stroke
				(width 0.1)
				(type default)
			)
			(layer "B.Fab")
		)
		(fp_line
			(start -0.3048 0.9906)
			(end -0.3048 -0.1016)
			(stroke
				(width 0.1)
				(type default)
			)
			(layer "B.Fab")
		)
		(fp_line
			(start 0.3048 -0.1016)
			(end 0.3048 0.9906)
			(stroke
				(width 0.1)
				(type default)
			)
			(layer "B.Fab")
		)
		(fp_line
			(start 0.3048 0.9906)
			(end -0.3048 0.9906)
			(stroke
				(width 0.1)
				(type default)
			)
			(layer "B.Fab")
		)
		(pad "1" smd rect
			(at 0 0 180)
			(size 0.508 0.508)
			(layers "B.Cu" "B.Mask" "B.Paste")
			(net "A_P3V3_STBY_SCALED")
		)
		(pad "2" smd rect
			(at 0 0.889 180)
			(size 0.508 0.508)
			(layers "B.Cu" "B.Mask" "B.Paste")
			(net "GND")
		)
		(zone
			(layer "B.Cu")
			(hatch none 0.5)
			(connect_pads
				(clearance 0)
			)
			(min_thickness 0.25)
			(keepout
				(tracks allowed)
				(vias not_allowed)
				(pads allowed)
				(copperpour not_allowed)
				(footprints allowed)
			)
			(placement
				(enabled no)
				(sheetname "")
			)
			(fill
				(thermal_gap 0.5)
				(thermal_bridge_width 0.5)
				(island_removal_mode 0)
			)
			(polygon
				(pts
					(xy 405.167846 -26.235152) (xy 404.659846 -26.235152) (xy 404.659846 -25.854152) (xy 405.167846 -25.854152)
				)
			)
		)
		(zone
			(layer "B.Cu")
			(hatch none 0.5)
			(connect_pads
				(clearance 0)
			)
			(min_thickness 0.25)
			(keepout
				(tracks not_allowed)
				(vias allowed)
				(pads allowed)
				(copperpour not_allowed)
				(footprints allowed)
			)
			(placement
				(enabled no)
				(sheetname "")
			)
			(fill
				(thermal_gap 0.5)
				(thermal_bridge_width 0.5)
				(island_removal_mode 0)
			)
			(polygon
				(pts
					(xy 405.167846 -25.854152) (xy 404.659846 -25.854152) (xy 404.659846 -26.235152) (xy 405.167846 -26.235152)
				)
			)
		)
	)
	(footprint ""
		(layer "B.Cu")
		(at 418.6936 -15.296134 180)
		(property "Reference" "Q2T2"
			(at 1.26873 2.4638 90)
			(unlocked yes)
			(layer "B.SilkS")
			(effects
				(font
					(size 0.7874 0.5842)
					(thickness 0.1524)
				)
				(justify left mirror)
			)
		)
		(property "Value" ""
			(at 0 0 0)
			(layer "B.Fab")
			(effects
				(font
					(size 1.27 1.27)
				)
				(justify mirror)
			)
		)
		(duplicate_pad_numbers_are_jumpers no)
		(fp_line
			(start -0.381 0.635)
			(end -0.381 1.27)
			(stroke
				(width 0.1524)
				(type default)
			)
			(layer "B.SilkS")
		)
		(fp_line
			(start -0.9525 2.4765)
			(end -1.778 2.4765)
			(stroke
				(width 0.1524)
				(type default)
			)
			(layer "B.SilkS")
		)
		(fp_line
			(start -0.9525 -0.5715)
			(end -1.778 -0.5715)
			(stroke
				(width 0.1524)
				(type default)
			)
			(layer "B.SilkS")
		)
		(fp_line
			(start -1.778 2.4765)
			(end -1.778 1.5875)
			(stroke
				(width 0.1524)
				(type default)
			)
			(layer "B.SilkS")
		)
		(fp_line
			(start -1.778 -0.5715)
			(end -1.778 0.3175)
			(stroke
				(width 0.1524)
				(type default)
			)
			(layer "B.SilkS")
		)
		(fp_circle
			(center 0.9525 -0.9271)
			(end 0.8255 -0.9271)
			(stroke
				(width 0.254)
				(type default)
			)
			(fill no)
			(layer "B.SilkS")
		)
		(fp_poly
			(pts
				(xy -1.778 2.4765) (xy -0.381 2.4765) (xy -0.381 -0.5715) (xy -1.778 -0.5715)
			)
			(stroke
				(width 0)
				(type default)
			)
			(fill no)
			(layer "B.CrtYd")
		)
		(fp_line
			(start -0.381 2.4765)
			(end -1.778 2.4765)
			(stroke
				(width 0.1)
				(type default)
			)
			(layer "B.Fab")
		)
		(fp_line
			(start -0.381 -0.5715)
			(end -0.381 2.4765)
			(stroke
				(width 0.1)
				(type default)
			)
			(layer "B.Fab")
		)
		(fp_line
			(start -1.778 2.4765)
			(end -1.778 -0.5715)
			(stroke
				(width 0.1)
				(type default)
			)
			(layer "B.Fab")
		)
		(fp_line
			(start -1.778 -0.5715)
			(end -0.381 -0.5715)
			(stroke
				(width 0.1)
				(type default)
			)
			(layer "B.Fab")
		)
		(fp_circle
			(center 0.9525 -0.9271)
			(end 0.8255 -0.9271)
			(stroke
				(width 0.254)
				(type default)
			)
			(fill no)
			(layer "B.Fab")
		)
		(pad "1" smd rect
			(at 0 0)
			(size 1.143 0.508)
			(layers "B.Cu" "B.Mask" "B.Paste")
			(net "H_CPU0_FAST_WAKE")
		)
		(pad "2" smd rect
			(at 0 1.905)
			(size 1.143 0.508)
			(layers "B.Cu" "B.Mask" "B.Paste")
			(net "GND")
		)
		(pad "3" smd rect
			(at -2.159 0.9525)
			(size 1.143 0.508)
			(layers "B.Cu" "B.Mask" "B.Paste")
			(net "H_CPU0_FAST_WAKE_LVT3_N")
		)
	)
)
